(kicad_pcb
	(version 20260206)
	(generator "pcbnew")
	(generator_version "10.0")
	(general
		(thickness 1.6)
		(legacy_teardrops no)
	)
	(paper "A4")
	(title_block
		(title "Bryce Canyon_R.DPB_16317-1_OCP.brd")
		(comment 1 "Bryce Canyon / footprints 1954-1961 of 2099")
	)
	(layers
		(0 "F.Cu" signal "TOP")
		(4 "In1.Cu" signal "L2GND")
		(6 "In2.Cu" signal "L3")
		(8 "In3.Cu" signal "L4VCC")
		(10 "In4.Cu" signal "L5VCC")
		(12 "In5.Cu" signal "L6")
		(14 "In6.Cu" signal "L7GND")
		(2 "B.Cu" signal "BOTTOM")
		(9 "F.Adhes" user "F.Adhesive")
		(11 "B.Adhes" user "B.Adhesive")
		(13 "F.Paste" user "Package Geometry/Pastemask Top")
		(15 "B.Paste" user "Package Geometry/Pastemask Bottom")
		(5 "F.SilkS" user "Ref Des/Silkscreen Top")
		(7 "B.SilkS" user "Ref Des/Silkscreen Bottom")
		(1 "F.Mask" user "Board Geometry/Soldermask Top")
		(3 "B.Mask" user "Board Geometry/Soldermask Bottom")
		(17 "Dwgs.User" user "User.Drawings")
		(19 "Cmts.User" user "User.Comments")
		(21 "Eco1.User" user "User.Eco1")
		(23 "Eco2.User" user "User.Eco2")
		(25 "Edge.Cuts" user "Board Geometry/Outline")
		(27 "Margin" user)
		(31 "F.CrtYd" user "Package Geometry/Place Bound Top")
		(29 "B.CrtYd" user "Package Geometry/Place Bound Bottom")
		(35 "F.Fab" user "Ref Des/Assembly Top")
		(33 "B.Fab" user "Ref Des/Assembly Bottom")
	)
	(footprint ""
		(layer "B.Cu")
		(at 127.431546 -364.12297 180)
		(property "Reference" "D50"
			(at 0 0 0)
			(layer "B.SilkS")
			(hide yes)
			(effects
				(font
					(size 1.27 1.27)
				)
				(justify mirror)
			)
		)
		(property "Value" "RB551V30-GP"
			(at 0 -6.7818 180)
			(unlocked yes)
			(layer "B.Fab")
			(hide yes)
			(effects
				(font
					(size 1.016 1.016)
					(thickness 0.1524)
				)
				(justify mirror)
			)
		)
		(property "Device Type" "SOD323AKH38"
			(at 0 -8.6868 180)
			(unlocked yes)
			(layer "B.Fab")
			(hide yes)
			(effects
				(font
					(size 1.016 1.016)
					(thickness 0.1524)
				)
				(justify mirror)
			)
		)
		(duplicate_pad_numbers_are_jumpers no)
		(fp_line
			(start 0.889 2.159)
			(end 0.889 -1.9304)
			(stroke
				(width 0.1524)
				(type default)
			)
			(layer "B.SilkS")
		)
		(fp_line
			(start 0.889 -1.9304)
			(end -0.889 -1.9304)
			(stroke
				(width 0.1524)
				(type default)
			)
			(layer "B.SilkS")
		)
		(fp_line
			(start -0.762 2.0574)
			(end 0.762 2.0574)
			(stroke
				(width 0.508)
				(type default)
			)
			(layer "B.SilkS")
		)
		(fp_line
			(start -0.889 2.159)
			(end 0.889 2.159)
			(stroke
				(width 0.1524)
				(type default)
			)
			(layer "B.SilkS")
		)
		(fp_line
			(start -0.889 -1.9304)
			(end -0.889 2.159)
			(stroke
				(width 0.1524)
				(type default)
			)
			(layer "B.SilkS")
		)
		(fp_rect
			(start 1.016 2.3114)
			(end -1.016 -2.0066)
			(stroke
				(width 0)
				(type default)
			)
			(fill no)
			(layer "B.CrtYd")
		)
		(fp_poly
			(pts
				(xy 1.016 -2.0066) (xy -1.016 -2.0066) (xy -1.016 2.3114) (xy 1.016 2.3114)
			)
			(stroke
				(width 0)
				(type default)
			)
			(fill no)
			(layer "B.Fab")
		)
		(pad "A" smd rect
			(at 0 -1.143)
			(size 0.5588 1.016)
			(layers "B.Cu" "B.Mask" "B.Paste")
			(net "GATE_FAN1")
		)
		(pad "K" smd rect
			(at 0 1.143)
			(size 0.5588 1.016)
			(layers "B.Cu" "B.Mask" "B.Paste")
			(net "GATE_FAN1_R")
		)
	)
	(footprint ""
		(layer "B.Cu")
		(at 41.0972 -219.96019)
		(property "Reference" "TC14"
			(at 0 0 0)
			(layer "B.SilkS")
			(hide yes)
			(effects
				(font
					(size 1.27 1.27)
				)
				(justify mirror)
			)
		)
		(property "Value" "ST220U10VDM-LGP"
			(at 0 -9.6012 0)
			(unlocked yes)
			(layer "B.Fab")
			(hide yes)
			(effects
				(font
					(size 1.016 1.016)
					(thickness 0.1524)
				)
				(justify mirror)
			)
		)
		(property "Device Type" "CT7343H119"
			(at 0 -11.1252 0)
			(unlocked yes)
			(layer "B.Fab")
			(hide yes)
			(effects
				(font
					(size 1.016 1.016)
					(thickness 0.1524)
				)
				(justify mirror)
			)
		)
		(duplicate_pad_numbers_are_jumpers no)
		(fp_line
			(start -2.286 -4.8768)
			(end 2.286 -4.8768)
			(stroke
				(width 0.1524)
				(type default)
			)
			(layer "B.SilkS")
		)
		(fp_line
			(start -2.286 -2.032)
			(end -2.286 -4.8768)
			(stroke
				(width 0.1524)
				(type default)
			)
			(layer "B.SilkS")
		)
		(fp_line
			(start -2.286 2.032)
			(end -2.286 4.8768)
			(stroke
				(width 0.1524)
				(type default)
			)
			(layer "B.SilkS")
		)
		(fp_line
			(start -2.286 4.8768)
			(end 2.286 4.8768)
			(stroke
				(width 0.1524)
				(type default)
			)
			(layer "B.SilkS")
		)
		(fp_line
			(start -2.1082 -4.699)
			(end 2.1082 -4.699)
			(stroke
				(width 0.508)
				(type default)
			)
			(layer "B.SilkS")
		)
		(fp_line
			(start 2.286 -4.8768)
			(end 2.286 -2.032)
			(stroke
				(width 0.1524)
				(type default)
			)
			(layer "B.SilkS")
		)
		(fp_line
			(start 2.286 4.8768)
			(end 2.286 2.032)
			(stroke
				(width 0.1524)
				(type default)
			)
			(layer "B.SilkS")
		)
		(fp_rect
			(start 2.1463 3.6449)
			(end -2.1463 -3.6449)
			(stroke
				(width 0)
				(type default)
			)
			(fill no)
			(layer "B.CrtYd")
		)
		(fp_poly
			(pts
				(xy 2.54 4.953) (xy 2.54 4.2926) (xy 3.81 4.2926) (xy 3.81 -4.2926) (xy 2.54 -4.2926) (xy 2.54 -4.953)
				(xy -2.54 -4.953) (xy -2.54 -4.2926) (xy -3.81 -4.2926) (xy -3.81 -1.6256) (xy -2.1463 -1.6256)
				(xy -2.1463 -3.6449) (xy 2.1463 -3.6449) (xy 2.1463 3.6449) (xy -2.1463 3.6449) (xy -2.1463 -1.6129)
				(xy -3.81 -1.6129) (xy -3.81 4.2926) (xy -2.54 4.2926) (xy -2.54 4.953)
			)
			(stroke
				(width 0)
				(type default)
			)
			(fill no)
			(layer "B.CrtYd")
		)
		(fp_rect
			(start -2.54 4.2926)
			(end -3.81 -4.2926)
			(stroke
				(width 0)
				(type default)
			)
			(fill no)
			(layer "B.Fab")
		)
		(fp_rect
			(start 2.54 4.953)
			(end -2.54 -4.953)
			(stroke
				(width 0)
				(type default)
			)
			(fill no)
			(layer "B.Fab")
		)
		(fp_rect
			(start 3.81 4.2926)
			(end 2.54 -4.2926)
			(stroke
				(width 0)
				(type default)
			)
			(fill no)
			(layer "B.Fab")
		)
		(pad "1" smd rect
			(at 0 -3.1496 180)
			(size 2.413 2.286)
			(layers "B.Cu" "B.Mask" "B.Paste")
			(net "P5V_B_1")
		)
		(pad "2" smd rect
			(at 0 3.1496 180)
			(size 2.413 2.286)
			(layers "B.Cu" "B.Mask" "B.Paste")
			(net "GND")
		)
		(zone
			(layer "B.Cu")
			(hatch none 0.5)
			(connect_pads
				(clearance 0)
			)
			(min_thickness 0.25)
			(keepout
				(tracks allowed)
				(vias not_allowed)
				(pads allowed)
				(copperpour not_allowed)
				(footprints allowed)
			)
			(placement
				(enabled no)
				(sheetname "")
			)
			(fill
				(thermal_gap 0.5)
				(thermal_bridge_width 0.5)
				(island_removal_mode 0)
			)
			(polygon
				(pts
					(xy 39.5859 -221.64929) (xy 39.5859 -224.55759) (xy 42.6085 -224.55759) (xy 42.6085 -221.66199)
					(xy 42.6085 -221.33179) (xy 39.5859 -221.33179)
				)
			)
		)
		(zone
			(layer "B.Cu")
			(hatch none 0.5)
			(connect_pads
				(clearance 0)
			)
			(min_thickness 0.25)
			(keepout
				(tracks allowed)
				(vias not_allowed)
				(pads allowed)
				(copperpour not_allowed)
				(footprints allowed)
			)
			(placement
				(enabled no)
				(sheetname "")
			)
			(fill
				(thermal_gap 0.5)
				(thermal_bridge_width 0.5)
				(island_removal_mode 0)
			)
			(polygon
				(pts
					(xy 42.6085 -215.36279) (xy 39.5859 -215.36279) (xy 39.5859 -218.25839) (xy 39.5859 -218.58859)
					(xy 42.6085 -218.58859) (xy 42.6085 -218.25839)
				)
			)
		)
	)
	(footprint ""
		(layer "B.Cu")
		(at 451.424802 -223.27235 180)
		(property "Reference" "C656"
			(at 0 0 0)
			(layer "B.SilkS")
			(hide yes)
			(effects
				(font
					(size 1.27 1.27)
				)
				(justify mirror)
			)
		)
		(property "Value" "SCD1U16V2KX-3GP"
			(at -1.1811 -2.7051 180)
			(unlocked yes)
			(layer "B.Fab")
			(hide yes)
			(effects
				(font
					(size 1.016 1.016)
					(thickness 0.1524)
				)
				(justify mirror)
			)
		)
		(property "Device Type" "C402H22"
			(at -1.1811 -4.2291 180)
			(unlocked yes)
			(layer "B.Fab")
			(hide yes)
			(effects
				(font
					(size 1.016 1.016)
					(thickness 0.1524)
				)
				(justify mirror)
			)
		)
		(duplicate_pad_numbers_are_jumpers no)
		(fp_rect
			(start 0.4318 0.9525)
			(end -0.4318 -0.9525)
			(stroke
				(width 0)
				(type default)
			)
			(fill no)
			(layer "B.CrtYd")
		)
		(fp_rect
			(start 0.4318 0.9525)
			(end -0.4318 -0.9525)
			(stroke
				(width 0)
				(type default)
			)
			(fill no)
			(layer "B.Fab")
		)
		(pad "1" smd custom
			(at 0 -0.4445)
			(size 0.1524 0.1524)
			(layers "B.Cu" "B.Mask" "B.Paste")
			(net "P12V_B_3_VIN_U33")
			(options
				(clearance outline)
				(anchor circle)
			)
			(primitives
				(gr_poly
					(pts
						(arc
							(start 0.3048 0.2032)
							(mid 0.275042 0.275042)
							(end 0.2032 0.3048)
						)
						(arc
							(start -0.2032 0.3048)
							(mid -0.275042 0.275042)
							(end -0.3048 0.2032)
						)
						(arc
							(start -0.3048 -0.2032)
							(mid -0.275042 -0.275042)
							(end -0.2032 -0.3048)
						)
						(arc
							(start 0.2032 -0.3048)
							(mid 0.275042 -0.275042)
							(end 0.3048 -0.2032)
						)
					)
					(width 0)
					(fill yes)
				)
			)
		)
		(pad "2" smd custom
			(at 0 0.4445)
			(size 0.1524 0.1524)
			(layers "B.Cu" "B.Mask" "B.Paste")
			(net "GND")
			(options
				(clearance outline)
				(anchor circle)
			)
			(primitives
				(gr_poly
					(pts
						(arc
							(start 0.3048 0.2032)
							(mid 0.275042 0.275042)
							(end 0.2032 0.3048)
						)
						(arc
							(start -0.2032 0.3048)
							(mid -0.275042 0.275042)
							(end -0.3048 0.2032)
						)
						(arc
							(start -0.3048 -0.2032)
							(mid -0.275042 -0.275042)
							(end -0.2032 -0.3048)
						)
						(arc
							(start 0.2032 -0.3048)
							(mid 0.275042 -0.275042)
							(end 0.3048 -0.2032)
						)
					)
					(width 0)
					(fill yes)
				)
			)
		)
	)
	(footprint ""
		(layer "B.Cu")
		(at 260.0198 -285.0896 -90)
		(property "Reference" "C699"
			(at 0 0 90)
			(layer "B.SilkS")
			(hide yes)
			(effects
				(font
					(size 1.27 1.27)
				)
				(justify mirror)
			)
		)
		(property "Value" "SC1KP50V2KX-1GP"
			(at -1.1811 -2.7051 270)
			(unlocked yes)
			(layer "B.Fab")
			(hide yes)
			(effects
				(font
					(size 1.016 1.016)
					(thickness 0.1524)
				)
				(justify mirror)
			)
		)
		(property "Device Type" "C402H22"
			(at -1.1811 -4.2291 270)
			(unlocked yes)
			(layer "B.Fab")
			(hide yes)
			(effects
				(font
					(size 1.016 1.016)
					(thickness 0.1524)
				)
				(justify mirror)
			)
		)
		(duplicate_pad_numbers_are_jumpers no)
		(fp_rect
			(start 0.4318 0.9525)
			(end -0.4318 -0.9525)
			(stroke
				(width 0)
				(type default)
			)
			(fill no)
			(layer "B.CrtYd")
		)
		(fp_rect
			(start 0.4318 0.9525)
			(end -0.4318 -0.9525)
			(stroke
				(width 0)
				(type default)
			)
			(fill no)
			(layer "B.Fab")
		)
		(pad "1" smd custom
			(at 0 -0.4445 90)
			(size 0.1524 0.1524)
			(layers "B.Cu" "B.Mask" "B.Paste")
			(net "P3V3_STBY_VFB_R")
			(options
				(clearance outline)
				(anchor circle)
			)
			(primitives
				(gr_poly
					(pts
						(arc
							(start 0.3048 0.2032)
							(mid 0.275042 0.275042)
							(end 0.2032 0.3048)
						)
						(arc
							(start -0.2032 0.3048)
							(mid -0.275042 0.275042)
							(end -0.3048 0.2032)
						)
						(arc
							(start -0.3048 -0.2032)
							(mid -0.275042 -0.275042)
							(end -0.2032 -0.3048)
						)
						(arc
							(start 0.2032 -0.3048)
							(mid 0.275042 -0.275042)
							(end 0.3048 -0.2032)
						)
					)
					(width 0)
					(fill yes)
				)
			)
		)
		(pad "2" smd custom
			(at 0 0.4445 90)
			(size 0.1524 0.1524)
			(layers "B.Cu" "B.Mask" "B.Paste")
			(net "P3V3_STBY_VFB")
			(options
				(clearance outline)
				(anchor circle)
			)
			(primitives
				(gr_poly
					(pts
						(arc
							(start 0.3048 0.2032)
							(mid 0.275042 0.275042)
							(end 0.2032 0.3048)
						)
						(arc
							(start -0.2032 0.3048)
							(mid -0.275042 0.275042)
							(end -0.3048 0.2032)
						)
						(arc
							(start -0.3048 -0.2032)
							(mid -0.275042 -0.275042)
							(end -0.2032 -0.3048)
						)
						(arc
							(start 0.2032 -0.3048)
							(mid 0.275042 -0.275042)
							(end 0.3048 -0.2032)
						)
					)
					(width 0)
					(fill yes)
				)
			)
		)
	)
	(footprint ""
		(layer "B.Cu")
		(at 251.714 -290.703 -90)
		(property "Reference" "C693"
			(at 0 0 90)
			(layer "B.SilkS")
			(hide yes)
			(effects
				(font
					(size 1.27 1.27)
				)
				(justify mirror)
			)
		)
		(property "Value" "SC10U16V5KX-7-GP-U"
			(at 0.0762 -6.1214 270)
			(unlocked yes)
			(layer "B.Fab")
			(hide yes)
			(effects
				(font
					(size 1.016 1.016)
					(thickness 0.1524)
				)
				(justify mirror)
			)
		)
		(property "Device Type" "C805H58"
			(at 0.0762 -8.1534 270)
			(unlocked yes)
			(layer "B.Fab")
			(hide yes)
			(effects
				(font
					(size 1.016 1.016)
					(thickness 0.1524)
				)
				(justify mirror)
			)
		)
		(duplicate_pad_numbers_are_jumpers no)
		(fp_line
			(start -0.635 0)
			(end 0.635 0)
			(stroke
				(width 0.508)
				(type default)
			)
			(layer "B.SilkS")
		)
		(fp_rect
			(start 0.9652 1.778)
			(end -0.9652 -1.778)
			(stroke
				(width 0)
				(type default)
			)
			(fill no)
			(layer "B.CrtYd")
		)
		(fp_poly
			(pts
				(xy 0.9652 -1.778) (xy -0.9652 -1.778) (xy -0.9652 1.778) (xy 0.9652 1.778)
			)
			(stroke
				(width 0)
				(type default)
			)
			(fill no)
			(layer "B.Fab")
		)
		(pad "1" smd rect
			(at 0 -0.9652 90)
			(size 1.397 1.143)
			(layers "B.Cu" "B.Mask" "B.Paste")
			(net "P3V3_STBY_VIN")
		)
		(pad "2" smd rect
			(at 0 0.9652 90)
			(size 1.397 1.143)
			(layers "B.Cu" "B.Mask" "B.Paste")
			(net "GND")
		)
	)
	(footprint ""
		(layer "B.Cu")
		(at 462.794604 -229.626414 -90)
		(property "Reference" "R1144"
			(at 0 0 90)
			(layer "B.SilkS")
			(hide yes)
			(effects
				(font
					(size 1.27 1.27)
				)
				(justify mirror)
			)
		)
		(property "Value" "10R3F-GP"
			(at 0.0254 -2.5146 270)
			(unlocked yes)
			(layer "B.Fab")
			(hide yes)
			(effects
				(font
					(size 1.016 1.016)
					(thickness 0.1524)
				)
				(justify mirror)
			)
		)
		(property "Device Type" "R603H22"
			(at 0.0254 -4.0386 270)
			(unlocked yes)
			(layer "B.Fab")
			(hide yes)
			(effects
				(font
					(size 1.016 1.016)
					(thickness 0.1524)
				)
				(justify mirror)
			)
		)
		(duplicate_pad_numbers_are_jumpers no)
		(fp_line
			(start -0.2032 0)
			(end -0.4826 0)
			(stroke
				(width 0.2032)
				(type default)
			)
			(layer "B.SilkS")
		)
		(fp_line
			(start 0.4826 0)
			(end 0.2032 0)
			(stroke
				(width 0.2032)
				(type default)
			)
			(layer "B.SilkS")
		)
		(fp_rect
			(start 0.5842 1.3335)
			(end -0.5842 -1.3335)
			(stroke
				(width 0)
				(type default)
			)
			(fill no)
			(layer "B.CrtYd")
		)
		(fp_rect
			(start 0.5842 1.3335)
			(end -0.5842 -1.3335)
			(stroke
				(width 0)
				(type default)
			)
			(fill no)
			(layer "B.Fab")
		)
		(pad "1" smd custom
			(at 0 -0.762 90)
			(size 0.2159 0.2159)
			(layers "B.Cu" "B.Mask" "B.Paste")
			(net "P5V_B_3_CC")
			(options
				(clearance outline)
				(anchor circle)
			)
			(primitives
				(gr_poly
					(pts
						(arc
							(start -0.3302 0.4318)
							(mid -0.402042 0.402042)
							(end -0.4318 0.3302)
						)
						(arc
							(start -0.4318 -0.3302)
							(mid -0.402042 -0.402042)
							(end -0.3302 -0.4318)
						)
						(arc
							(start 0.3302 -0.4318)
							(mid 0.402042 -0.402042)
							(end 0.4318 -0.3302)
						)
						(arc
							(start 0.4318 0.3302)
							(mid 0.402042 0.402042)
							(end 0.3302 0.4318)
						)
					)
					(width 0)
					(fill yes)
				)
			)
		)
		(pad "2" smd custom
			(at 0 0.762 90)
			(size 0.2159 0.2159)
			(layers "B.Cu" "B.Mask" "B.Paste")
			(net "P5V_B_3_VFB_R")
			(options
				(clearance outline)
				(anchor circle)
			)
			(primitives
				(gr_poly
					(pts
						(arc
							(start -0.3302 0.4318)
							(mid -0.402042 0.402042)
							(end -0.4318 0.3302)
						)
						(arc
							(start -0.4318 -0.3302)
							(mid -0.402042 -0.402042)
							(end -0.3302 -0.4318)
						)
						(arc
							(start 0.3302 -0.4318)
							(mid 0.402042 -0.402042)
							(end 0.4318 -0.3302)
						)
						(arc
							(start 0.4318 0.3302)
							(mid 0.402042 0.402042)
							(end 0.3302 0.4318)
						)
					)
					(width 0)
					(fill yes)
				)
			)
		)
	)
	(footprint ""
		(layer "B.Cu")
		(at 255.775206 -277.451312 90)
		(property "Reference" "R1184"
			(at 0 0 90)
			(layer "B.SilkS")
			(hide yes)
			(effects
				(font
					(size 1.27 1.27)
				)
				(justify mirror)
			)
		)
		(property "Value" "0R2J-2-GP"
			(at -0.064008 -3.993896 90)
			(unlocked yes)
			(layer "B.Fab")
			(hide yes)
			(effects
				(font
					(size 1.016 1.016)
					(thickness 0.1524)
				)
				(justify mirror)
			)
		)
		(property "Device Type" "R402H16"
			(at -0.064008 -5.517896 90)
			(unlocked yes)
			(layer "B.Fab")
			(hide yes)
			(effects
				(font
					(size 1.016 1.016)
					(thickness 0.1524)
				)
				(justify mirror)
			)
		)
		(duplicate_pad_numbers_are_jumpers no)
		(fp_line
			(start 0.508 -0.9398)
			(end 0.508 0.9398)
			(stroke
				(width 0.1524)
				(type default)
			)
			(layer "B.SilkS")
		)
		(fp_line
			(start -0.508 -0.9398)
			(end 0.508 -0.9398)
			(stroke
				(width 0.1524)
				(type default)
			)
			(layer "B.SilkS")
		)
		(fp_rect
			(start 0.508 0.9398)
			(end -0.508 -0.9398)
			(stroke
				(width 0)
				(type default)
			)
			(fill no)
			(layer "B.CrtYd")
		)
		(fp_rect
			(start 0.508 0.9398)
			(end -0.508 -0.9398)
			(stroke
				(width 0)
				(type default)
			)
			(fill no)
			(layer "B.Fab")
		)
		(pad "1" smd custom
			(at 0 -0.4445 270)
			(size 0.1397 0.1397)
			(layers "B.Cu" "B.Mask" "B.Paste")
			(net "P3V3_STBY_EN_R")
			(options
				(clearance outline)
				(anchor circle)
			)
			(primitives
				(gr_poly
					(pts
						(arc
							(start -0.1778 0.2794)
							(mid -0.249642 0.249642)
							(end -0.2794 0.1778)
						)
						(arc
							(start -0.2794 -0.1778)
							(mid -0.249642 -0.249642)
							(end -0.1778 -0.2794)
						)
						(arc
							(start 0.1778 -0.2794)
							(mid 0.249642 -0.249642)
							(end 0.2794 -0.1778)
						)
						(arc
							(start 0.2794 0.1778)
							(mid 0.249642 0.249642)
							(end 0.1778 0.2794)
						)
					)
					(width 0)
					(fill yes)
				)
			)
		)
		(pad "2" smd custom
			(at 0 0.4445 270)
			(size 0.1397 0.1397)
			(layers "B.Cu" "B.Mask" "B.Paste")
			(net "P12V_B_PGOOD")
			(options
				(clearance outline)
				(anchor circle)
			)
			(primitives
				(gr_poly
					(pts
						(arc
							(start -0.1778 0.2794)
							(mid -0.249642 0.249642)
							(end -0.2794 0.1778)
						)
						(arc
							(start -0.2794 -0.1778)
							(mid -0.249642 -0.249642)
							(end -0.1778 -0.2794)
						)
						(arc
							(start 0.1778 -0.2794)
							(mid 0.249642 -0.249642)
							(end 0.2794 -0.1778)
						)
						(arc
							(start 0.2794 0.1778)
							(mid 0.249642 0.249642)
							(end 0.1778 0.2794)
						)
					)
					(width 0)
					(fill yes)
				)
			)
		)
	)
	(footprint ""
		(layer "B.Cu")
		(at 240.705894 -277.824946 -90)
		(property "Reference" "C701"
			(at 0 0 90)
			(layer "B.SilkS")
			(hide yes)
			(effects
				(font
					(size 1.27 1.27)
				)
				(justify mirror)
			)
		)
		(property "Value" "SC10U6D3V5KX-4GP"
			(at 0.0762 -6.1214 270)
			(unlocked yes)
			(layer "B.Fab")
			(hide yes)
			(effects
				(font
					(size 1.016 1.016)
					(thickness 0.1524)
				)
				(justify mirror)
			)
		)
		(property "Device Type" "C805H58"
			(at 0.0762 -8.1534 270)
			(unlocked yes)
			(layer "B.Fab")
			(hide yes)
			(effects
				(font
					(size 1.016 1.016)
					(thickness 0.1524)
				)
				(justify mirror)
			)
		)
		(duplicate_pad_numbers_are_jumpers no)
		(fp_line
			(start -0.635 0)
			(end 0.635 0)
			(stroke
				(width 0.508)
				(type default)
			)
			(layer "B.SilkS")
		)
		(fp_rect
			(start 0.9652 1.778)
			(end -0.9652 -1.778)
			(stroke
				(width 0)
				(type default)
			)
			(fill no)
			(layer "B.CrtYd")
		)
		(fp_poly
			(pts
				(xy 0.9652 -1.778) (xy -0.9652 -1.778) (xy -0.9652 1.778) (xy 0.9652 1.778)
			)
			(stroke
				(width 0)
				(type default)
			)
			(fill no)
			(layer "B.Fab")
		)
		(pad "1" smd rect
			(at 0 -0.9652 90)
			(size 1.397 1.143)
			(layers "B.Cu" "B.Mask" "B.Paste")
			(net "P3V3_STBY_B")
		)
		(pad "2" smd rect
			(at 0 0.9652 90)
			(size 1.397 1.143)
			(layers "B.Cu" "B.Mask" "B.Paste")
			(net "GND")
		)
	)
)
